# S9S_MB_2U (Grand Teton) — schematic netlist excerpt (pin names and nets, part order shuffled) for the footprints in the layout excerpt that follows; sources: Cadence DE-HDL packaged netlist, KiCad conversion of 03242023_DA0F0TMBIJ0_F0T_Motherboard_J_brd_V01_OCP.brd

R2946  Q_RES  4.7K 5% EMPTY  pkg 0402LF  page 246 : A = P3V3_AUX ; B = FM_GPU_HSC_EN_BUF_R
R4410  Q_RES  1.5K 1% CHIP  pkg 0402LF  page 123 : A = H_CPU1_MEMTRIP ; B = H_CPU1_MEMTRIP_R

(kicad_pcb
	(version 20260206)
	(generator "pcbnew")
	(generator_version "10.0")
	(general
		(thickness 1.6)
		(legacy_teardrops no)
	)
	(paper "A4")
	(title_block
		(title "03242023_DA0F0TMBIJ0_F0T_Motherboard_J_brd_V01_OCP.brd")
		(comment 1 "Grand Teton / footprints 165-166 of 6105")
	)
	(layers
		(0 "F.Cu" signal "TOP")
		(4 "In1.Cu" signal "GND")
		(6 "In2.Cu" signal "IN1")
		(8 "In3.Cu" signal "GND1")
		(10 "In4.Cu" signal "IN2")
		(12 "In5.Cu" signal "GND2")
		(14 "In6.Cu" signal "IN3")
		(16 "In7.Cu" signal "GND3")
		(18 "In8.Cu" signal "VCC")
		(20 "In9.Cu" signal "VCC1")
		(22 "In10.Cu" signal "GND4")
		(24 "In11.Cu" signal "IN4")
		(26 "In12.Cu" signal "GND5")
		(28 "In13.Cu" signal "IN5")
		(30 "In14.Cu" signal "GND6")
		(32 "In15.Cu" signal "IN6")
		(34 "In16.Cu" signal "GND7")
		(2 "B.Cu" signal "BOTTOM")
		(9 "F.Adhes" user "F.Adhesive")
		(11 "B.Adhes" user "B.Adhesive")
		(13 "F.Paste" user "Package Geometry/Pastemask Top")
		(15 "B.Paste" user "Package Geometry/Pastemask Bottom")
		(5 "F.SilkS" user "Ref Des/Silkscreen Top")
		(7 "B.SilkS" user "Ref Des/Silkscreen Bottom")
		(1 "F.Mask" user "Board Geometry/Soldermask Top")
		(3 "B.Mask" user "Board Geometry/Soldermask Bottom")
		(17 "Dwgs.User" user "User.Drawings")
		(19 "Cmts.User" user "User.Comments")
		(21 "Eco1.User" user "User.Eco1")
		(23 "Eco2.User" user "User.Eco2")
		(25 "Edge.Cuts" user "Board Geometry/Outline")
		(27 "Margin" user)
		(31 "F.CrtYd" user "Package Geometry/Place Bound Top")
		(29 "B.CrtYd" user "Package Geometry/Place Bound Bottom")
		(35 "F.Fab" user "Ref Des/Assembly Top")
		(33 "B.Fab" user "Ref Des/Assembly Bottom")
	)
	(footprint ""
		(layer "F.Cu")
		(at 193.004186 -429.41113 90)
		(property "Reference" "R2946"
			(at 0 0 90)
			(layer "F.SilkS")
			(hide yes)
			(effects
				(font
					(size 1.27 1.27)
				)
			)
		)
		(property "Value" ""
			(at 0 0 90)
			(layer "F.Fab")
			(effects
				(font
					(size 1.27 1.27)
				)
			)
		)
		(duplicate_pad_numbers_are_jumpers no)
		(fp_line
			(start 0.7874 -0.4064)
			(end 0.7874 0.4064)
			(stroke
				(width 0.1524)
				(type default)
			)
			(layer "F.SilkS")
		)
		(fp_line
			(start -0.7874 -0.4064)
			(end 0.7874 -0.4064)
			(stroke
				(width 0.1524)
				(type default)
			)
			(layer "F.SilkS")
		)
		(fp_line
			(start 0.7874 0.4064)
			(end -0.7874 0.4064)
			(stroke
				(width 0.1524)
				(type default)
			)
			(layer "F.SilkS")
		)
		(fp_line
			(start -0.7874 0.4064)
			(end -0.7874 -0.4064)
			(stroke
				(width 0.1524)
				(type default)
			)
			(layer "F.SilkS")
		)
		(fp_line
			(start -0.12065 -0.305054)
			(end -0.12065 -0.2794)
			(stroke
				(width 0.1)
				(type default)
			)
			(layer "F.Fab")
		)
		(fp_line
			(start -0.67945 -0.305054)
			(end -0.12065 -0.305054)
			(stroke
				(width 0.1)
				(type default)
			)
			(layer "F.Fab")
		)
		(fp_line
			(start 0.67945 -0.3048)
			(end 0.67945 0.3048)
			(stroke
				(width 0.1)
				(type default)
			)
			(layer "F.Fab")
		)
		(fp_line
			(start 0.12065 -0.3048)
			(end 0.67945 -0.3048)
			(stroke
				(width 0.1)
				(type default)
			)
			(layer "F.Fab")
		)
		(fp_line
			(start 0.12065 -0.2794)
			(end 0.12065 -0.3048)
			(stroke
				(width 0.1)
				(type default)
			)
			(layer "F.Fab")
		)
		(fp_line
			(start -0.12065 -0.2794)
			(end 0.12065 -0.2794)
			(stroke
				(width 0.1)
				(type default)
			)
			(layer "F.Fab")
		)
		(fp_line
			(start 0.120396 0.2794)
			(end -0.12065 0.2794)
			(stroke
				(width 0.1)
				(type default)
			)
			(layer "F.Fab")
		)
		(fp_line
			(start -0.12065 0.2794)
			(end -0.12065 0.3048)
			(stroke
				(width 0.1)
				(type default)
			)
			(layer "F.Fab")
		)
		(fp_line
			(start 0.67945 0.3048)
			(end 0.120396 0.3048)
			(stroke
				(width 0.1)
				(type default)
			)
			(layer "F.Fab")
		)
		(fp_line
			(start 0.120396 0.3048)
			(end 0.120396 0.2794)
			(stroke
				(width 0.1)
				(type default)
			)
			(layer "F.Fab")
		)
		(fp_line
			(start -0.12065 0.3048)
			(end -0.67945 0.3048)
			(stroke
				(width 0.1)
				(type default)
			)
			(layer "F.Fab")
		)
		(fp_line
			(start -0.67945 0.3048)
			(end -0.67945 -0.305054)
			(stroke
				(width 0.1)
				(type default)
			)
			(layer "F.Fab")
		)
		(pad "1" smd circle
			(at -0.40005 0 90)
			(size 0 0)
			(layers "F.Cu" "F.Mask" "F.Paste")
			(net "P3V3_AUX")
		)
		(pad "2" smd circle
			(at 0.40005 0 90)
			(size 0 0)
			(layers "F.Cu" "F.Mask" "F.Paste")
			(net "FM_GPU_HSC_EN_BUF_R")
		)
	)
	(footprint ""
		(layer "F.Cu")
		(at 133.27888 -106.898948)
		(property "Reference" "R4410"
			(at 0 0 0)
			(layer "F.SilkS")
			(hide yes)
			(effects
				(font
					(size 1.27 1.27)
				)
			)
		)
		(property "Value" ""
			(at 0 0 0)
			(layer "F.Fab")
			(effects
				(font
					(size 1.27 1.27)
				)
			)
		)
		(duplicate_pad_numbers_are_jumpers no)
		(fp_line
			(start -0.7874 -0.4064)
			(end 0.7874 -0.4064)
			(stroke
				(width 0.1524)
				(type default)
			)
			(layer "F.SilkS")
		)
		(fp_line
			(start -0.7874 0.4064)
			(end -0.7874 -0.4064)
			(stroke
				(width 0.1524)
				(type default)
			)
			(layer "F.SilkS")
		)
		(fp_line
			(start 0.7874 -0.4064)
			(end 0.7874 0.4064)
			(stroke
				(width 0.1524)
				(type default)
			)
			(layer "F.SilkS")
		)
		(fp_line
			(start 0.7874 0.4064)
			(end -0.7874 0.4064)
			(stroke
				(width 0.1524)
				(type default)
			)
			(layer "F.SilkS")
		)
		(fp_line
			(start -0.67945 -0.305054)
			(end -0.12065 -0.305054)
			(stroke
				(width 0.1)
				(type default)
			)
			(layer "F.Fab")
		)
		(fp_line
			(start -0.67945 0.3048)
			(end -0.67945 -0.305054)
			(stroke
				(width 0.1)
				(type default)
			)
			(layer "F.Fab")
		)
		(fp_line
			(start -0.12065 -0.305054)
			(end -0.12065 -0.2794)
			(stroke
				(width 0.1)
				(type default)
			)
			(layer "F.Fab")
		)
		(fp_line
			(start -0.12065 -0.2794)
			(end 0.12065 -0.2794)
			(stroke
				(width 0.1)
				(type default)
			)
			(layer "F.Fab")
		)
		(fp_line
			(start -0.12065 0.2794)
			(end -0.12065 0.3048)
			(stroke
				(width 0.1)
				(type default)
			)
			(layer "F.Fab")
		)
		(fp_line
			(start -0.12065 0.3048)
			(end -0.67945 0.3048)
			(stroke
				(width 0.1)
				(type default)
			)
			(layer "F.Fab")
		)
		(fp_line
			(start 0.120396 0.2794)
			(end -0.12065 0.2794)
			(stroke
				(width 0.1)
				(type default)
			)
			(layer "F.Fab")
		)
		(fp_line
			(start 0.120396 0.3048)
			(end 0.120396 0.2794)
			(stroke
				(width 0.1)
				(type default)
			)
			(layer "F.Fab")
		)
		(fp_line
			(start 0.12065 -0.3048)
			(end 0.67945 -0.3048)
			(stroke
				(width 0.1)
				(type default)
			)
			(layer "F.Fab")
		)
		(fp_line
			(start 0.12065 -0.2794)
			(end 0.12065 -0.3048)
			(stroke
				(width 0.1)
				(type default)
			)
			(layer "F.Fab")
		)
		(fp_line
			(start 0.67945 -0.3048)
			(end 0.67945 0.3048)
			(stroke
				(width 0.1)
				(type default)
			)
			(layer "F.Fab")
		)
		(fp_line
			(start 0.67945 0.3048)
			(end 0.120396 0.3048)
			(stroke
				(width 0.1)
				(type default)
			)
			(layer "F.Fab")
		)
		(pad "1" smd circle
			(at -0.40005 0)
			(size 0 0)
			(layers "F.Cu" "F.Mask" "F.Paste")
			(net "H_CPU1_MEMTRIP")
		)
		(pad "2" smd circle
			(at 0.40005 0)
			(size 0 0)
			(layers "F.Cu" "F.Mask" "F.Paste")
			(net "H_CPU1_MEMTRIP_R")
		)
	)
)
